(kicad_pcb
	(version 20260206)
	(generator "pcbnew")
	(generator_version "10.0")
	(general
		(thickness 1.6)
		(legacy_teardrops no)
	)
	(paper "A4")
	(title_block
		(title "01162023_DA0F0TEBIF0_F0T_Expander_BD_F_brd_V02_OCP.brd")
		(comment 1 "Grand Teton / footprints 5610-5617 of 9728")
	)
	(layers
		(0 "F.Cu" signal "TOP")
		(4 "In1.Cu" signal "GND")
		(6 "In2.Cu" signal "VCC")
		(8 "In3.Cu" signal "VCC1")
		(10 "In4.Cu" signal "GND1")
		(12 "In5.Cu" signal "IN1")
		(14 "In6.Cu" signal "GND2")
		(16 "In7.Cu" signal "IN2")
		(18 "In8.Cu" signal "GND3")
		(20 "In9.Cu" signal "IN3")
		(22 "In10.Cu" signal "GND4")
		(24 "In11.Cu" signal "IN4")
		(26 "In12.Cu" signal "GND5")
		(28 "In13.Cu" signal "IN5")
		(30 "In14.Cu" signal "GND6")
		(32 "In15.Cu" signal "IN6")
		(34 "In16.Cu" signal "GND7")
		(2 "B.Cu" signal "BOTTOM")
		(9 "F.Adhes" user "F.Adhesive")
		(11 "B.Adhes" user "B.Adhesive")
		(13 "F.Paste" user "Package Geometry/Pastemask Top")
		(15 "B.Paste" user "Package Geometry/Pastemask Bottom")
		(5 "F.SilkS" user "Ref Des/Silkscreen Top")
		(7 "B.SilkS" user "Ref Des/Silkscreen Bottom")
		(1 "F.Mask" user "Board Geometry/Soldermask Top")
		(3 "B.Mask" user "Board Geometry/Soldermask Bottom")
		(17 "Dwgs.User" user "User.Drawings")
		(19 "Cmts.User" user "User.Comments")
		(21 "Eco1.User" user "User.Eco1")
		(23 "Eco2.User" user "User.Eco2")
		(25 "Edge.Cuts" user "Board Geometry/Outline")
		(27 "Margin" user)
		(31 "F.CrtYd" user "Package Geometry/Place Bound Top")
		(29 "B.CrtYd" user "Package Geometry/Place Bound Bottom")
		(35 "F.Fab" user "Ref Des/Assembly Top")
		(33 "B.Fab" user "Ref Des/Assembly Bottom")
	)
	(footprint ""
		(layer "F.Cu")
		(at 286.385 -83.566 180)
		(property "Reference" "R491"
			(at 0 0 180)
			(layer "F.SilkS")
			(hide yes)
			(effects
				(font
					(size 1.27 1.27)
				)
			)
		)
		(property "Value" ""
			(at 0 0 180)
			(layer "F.Fab")
			(effects
				(font
					(size 1.27 1.27)
				)
			)
		)
		(duplicate_pad_numbers_are_jumpers no)
		(fp_line
			(start 0.7874 0.4064)
			(end -0.7874 0.4064)
			(stroke
				(width 0.1524)
				(type default)
			)
			(layer "F.SilkS")
		)
		(fp_line
			(start 0.7874 -0.4064)
			(end 0.7874 0.4064)
			(stroke
				(width 0.1524)
				(type default)
			)
			(layer "F.SilkS")
		)
		(fp_line
			(start -0.7874 0.4064)
			(end -0.7874 -0.4064)
			(stroke
				(width 0.1524)
				(type default)
			)
			(layer "F.SilkS")
		)
		(fp_line
			(start -0.7874 -0.4064)
			(end 0.7874 -0.4064)
			(stroke
				(width 0.1524)
				(type default)
			)
			(layer "F.SilkS")
		)
		(fp_line
			(start 0.67945 0.3048)
			(end 0.120396 0.3048)
			(stroke
				(width 0.1)
				(type default)
			)
			(layer "F.Fab")
		)
		(fp_line
			(start 0.67945 -0.3048)
			(end 0.67945 0.3048)
			(stroke
				(width 0.1)
				(type default)
			)
			(layer "F.Fab")
		)
		(fp_line
			(start 0.12065 -0.2794)
			(end 0.12065 -0.3048)
			(stroke
				(width 0.1)
				(type default)
			)
			(layer "F.Fab")
		)
		(fp_line
			(start 0.12065 -0.3048)
			(end 0.67945 -0.3048)
			(stroke
				(width 0.1)
				(type default)
			)
			(layer "F.Fab")
		)
		(fp_line
			(start 0.120396 0.3048)
			(end 0.120396 0.2794)
			(stroke
				(width 0.1)
				(type default)
			)
			(layer "F.Fab")
		)
		(fp_line
			(start 0.120396 0.2794)
			(end -0.12065 0.2794)
			(stroke
				(width 0.1)
				(type default)
			)
			(layer "F.Fab")
		)
		(fp_line
			(start -0.12065 0.3048)
			(end -0.67945 0.3048)
			(stroke
				(width 0.1)
				(type default)
			)
			(layer "F.Fab")
		)
		(fp_line
			(start -0.12065 0.2794)
			(end -0.12065 0.3048)
			(stroke
				(width 0.1)
				(type default)
			)
			(layer "F.Fab")
		)
		(fp_line
			(start -0.12065 -0.2794)
			(end 0.12065 -0.2794)
			(stroke
				(width 0.1)
				(type default)
			)
			(layer "F.Fab")
		)
		(fp_line
			(start -0.12065 -0.305054)
			(end -0.12065 -0.2794)
			(stroke
				(width 0.1)
				(type default)
			)
			(layer "F.Fab")
		)
		(fp_line
			(start -0.67945 0.3048)
			(end -0.67945 -0.305054)
			(stroke
				(width 0.1)
				(type default)
			)
			(layer "F.Fab")
		)
		(fp_line
			(start -0.67945 -0.305054)
			(end -0.12065 -0.305054)
			(stroke
				(width 0.1)
				(type default)
			)
			(layer "F.Fab")
		)
		(pad "1" smd circle
			(at -0.40005 0 180)
			(size 0 0)
			(layers "F.Cu" "F.Mask" "F.Paste")
			(net "BB_FRU_A2")
		)
		(pad "2" smd circle
			(at 0.40005 0 180)
			(size 0 0)
			(layers "F.Cu" "F.Mask" "F.Paste")
			(net "GND")
		)
	)
	(footprint ""
		(layer "F.Cu")
		(at 488.19054 -546.564566 180)
		(property "Reference" "SCREW_SSD9_1"
			(at -5.207 -1.402334 0)
			(unlocked yes)
			(layer "B.SilkS")
			(effects
				(font
					(size 0.7874 0.5842)
					(thickness 0.1524)
				)
				(justify mirror)
			)
		)
		(property "Value" ""
			(at 0 0 180)
			(layer "F.Fab")
			(effects
				(font
					(size 1.27 1.27)
				)
			)
		)
		(duplicate_pad_numbers_are_jumpers no)
		(pad "1" thru_hole circle
			(at 0 0 180)
			(size 0.4572 0.4572)
			(drill 0.2032)
			(layers "*.Cu" "*.Mask")
			(remove_unused_layers no)
			(net "Net_9126")
			(clearance 0.127)
			(thermal_gap 0.127)
			(padstack
				(mode front_inner_back)
				(layer "Inner"
					(shape circle)
					(size 0.4572 0.4572)
					(clearance 0.127)
				)
				(layer "B.Cu"
					(shape circle)
					(size 0.508 0.508)
					(clearance 0.1016)
				)
			)
		)
	)
	(footprint ""
		(layer "F.Cu")
		(at 354.889562 -313.620404 180)
		(property "Reference" "L78"
			(at 0 0 180)
			(layer "F.SilkS")
			(hide yes)
			(effects
				(font
					(size 1.27 1.27)
				)
			)
		)
		(property "Value" ""
			(at 0 0 180)
			(layer "F.Fab")
			(effects
				(font
					(size 1.27 1.27)
				)
			)
		)
		(duplicate_pad_numbers_are_jumpers no)
		(fp_line
			(start 2.248154 4.9911)
			(end 2.248154 1.787144)
			(stroke
				(width 0.1524)
				(type default)
			)
			(layer "F.SilkS")
		)
		(fp_line
			(start 2.248154 -1.814322)
			(end 2.248154 -4.9911)
			(stroke
				(width 0.1524)
				(type default)
			)
			(layer "F.SilkS")
		)
		(fp_line
			(start 2.248154 -4.9911)
			(end -2.248154 -4.9911)
			(stroke
				(width 0.1524)
				(type default)
			)
			(layer "F.SilkS")
		)
		(fp_line
			(start -2.248154 4.9911)
			(end 2.248154 4.9911)
			(stroke
				(width 0.1524)
				(type default)
			)
			(layer "F.SilkS")
		)
		(fp_line
			(start -2.248154 1.69926)
			(end -2.248154 4.9911)
			(stroke
				(width 0.1524)
				(type default)
			)
			(layer "F.SilkS")
		)
		(fp_line
			(start -2.248154 -4.9911)
			(end -2.248154 -1.880108)
			(stroke
				(width 0.1524)
				(type default)
			)
			(layer "F.SilkS")
		)
		(fp_line
			(start 1.700022 0.899922)
			(end 1.700022 -0.899922)
			(stroke
				(width 0.1)
				(type default)
			)
			(layer "F.Fab")
		)
		(fp_line
			(start 1.700022 -0.899922)
			(end -1.700022 -0.899922)
			(stroke
				(width 0.1)
				(type default)
			)
			(layer "F.Fab")
		)
		(fp_line
			(start -1.700022 0.899922)
			(end 1.700022 0.899922)
			(stroke
				(width 0.1)
				(type default)
			)
			(layer "F.Fab")
		)
		(fp_line
			(start -1.700022 -0.899922)
			(end -1.700022 0.899922)
			(stroke
				(width 0.1)
				(type default)
			)
			(layer "F.Fab")
		)
		(pad "1" smd rect
			(at -1.575054 0 180)
			(size 1.1684 9.8044)
			(layers "F.Cu" "F.Mask" "F.Paste")
			(net "P0V8_PEX3")
		)
		(pad "2" smd rect
			(at 1.575054 0 180)
			(size 1.1684 9.8044)
			(layers "F.Cu" "F.Mask" "F.Paste")
			(net "P0V8_SERDES_VDDA_PEX3")
		)
	)
	(footprint ""
		(layer "F.Cu")
		(at 155.380436 -111.003334)
		(property "Reference" "C263"
			(at 0 0 0)
			(layer "F.SilkS")
			(hide yes)
			(effects
				(font
					(size 1.27 1.27)
				)
			)
		)
		(property "Value" ""
			(at 0 0 0)
			(layer "F.Fab")
			(effects
				(font
					(size 1.27 1.27)
				)
			)
		)
		(duplicate_pad_numbers_are_jumpers no)
		(fp_line
			(start -0.299974 -0.150114)
			(end 0.299974 -0.150114)
			(stroke
				(width 0.1)
				(type default)
			)
			(layer "F.Fab")
		)
		(fp_line
			(start -0.299974 0.150114)
			(end -0.299974 -0.150114)
			(stroke
				(width 0.1)
				(type default)
			)
			(layer "F.Fab")
		)
		(fp_line
			(start 0.299974 -0.150114)
			(end 0.299974 0.150114)
			(stroke
				(width 0.1)
				(type default)
			)
			(layer "F.Fab")
		)
		(fp_line
			(start 0.299974 0.150114)
			(end -0.299974 0.150114)
			(stroke
				(width 0.1)
				(type default)
			)
			(layer "F.Fab")
		)
		(pad "1" smd rect
			(at -0.2667 0)
			(size 0.3048 0.381)
			(layers "F.Cu" "F.Mask" "F.Paste")
			(net "P5E_PEX1_STN1_TX_DN<22>")
		)
		(pad "2" smd rect
			(at 0.2667 0)
			(size 0.3048 0.381)
			(layers "F.Cu" "F.Mask" "F.Paste")
			(net "P5E_PEX1_STN1_TX_C_DN<22>")
		)
	)
	(footprint ""
		(layer "F.Cu")
		(at 242.201954 -178.519328 -90)
		(property "Reference" "R4249"
			(at 0 0 270)
			(layer "F.SilkS")
			(hide yes)
			(effects
				(font
					(size 1.27 1.27)
				)
			)
		)
		(property "Value" ""
			(at 0 0 270)
			(layer "F.Fab")
			(effects
				(font
					(size 1.27 1.27)
				)
			)
		)
		(duplicate_pad_numbers_are_jumpers no)
		(fp_line
			(start -0.7874 0.4064)
			(end -0.7874 -0.4064)
			(stroke
				(width 0.1524)
				(type default)
			)
			(layer "F.SilkS")
		)
		(fp_line
			(start 0.7874 0.4064)
			(end -0.7874 0.4064)
			(stroke
				(width 0.1524)
				(type default)
			)
			(layer "F.SilkS")
		)
		(fp_line
			(start -0.7874 -0.4064)
			(end 0.7874 -0.4064)
			(stroke
				(width 0.1524)
				(type default)
			)
			(layer "F.SilkS")
		)
		(fp_line
			(start 0.7874 -0.4064)
			(end 0.7874 0.4064)
			(stroke
				(width 0.1524)
				(type default)
			)
			(layer "F.SilkS")
		)
		(fp_line
			(start -0.67945 0.3048)
			(end -0.67945 -0.305054)
			(stroke
				(width 0.1)
				(type default)
			)
			(layer "F.Fab")
		)
		(fp_line
			(start -0.12065 0.3048)
			(end -0.67945 0.3048)
			(stroke
				(width 0.1)
				(type default)
			)
			(layer "F.Fab")
		)
		(fp_line
			(start 0.120396 0.3048)
			(end 0.120396 0.2794)
			(stroke
				(width 0.1)
				(type default)
			)
			(layer "F.Fab")
		)
		(fp_line
			(start 0.67945 0.3048)
			(end 0.120396 0.3048)
			(stroke
				(width 0.1)
				(type default)
			)
			(layer "F.Fab")
		)
		(fp_line
			(start -0.12065 0.2794)
			(end -0.12065 0.3048)
			(stroke
				(width 0.1)
				(type default)
			)
			(layer "F.Fab")
		)
		(fp_line
			(start 0.120396 0.2794)
			(end -0.12065 0.2794)
			(stroke
				(width 0.1)
				(type default)
			)
			(layer "F.Fab")
		)
		(fp_line
			(start -0.12065 -0.2794)
			(end 0.12065 -0.2794)
			(stroke
				(width 0.1)
				(type default)
			)
			(layer "F.Fab")
		)
		(fp_line
			(start 0.12065 -0.2794)
			(end 0.12065 -0.3048)
			(stroke
				(width 0.1)
				(type default)
			)
			(layer "F.Fab")
		)
		(fp_line
			(start 0.12065 -0.3048)
			(end 0.67945 -0.3048)
			(stroke
				(width 0.1)
				(type default)
			)
			(layer "F.Fab")
		)
		(fp_line
			(start 0.67945 -0.3048)
			(end 0.67945 0.3048)
			(stroke
				(width 0.1)
				(type default)
			)
			(layer "F.Fab")
		)
		(fp_line
			(start -0.67945 -0.305054)
			(end -0.12065 -0.305054)
			(stroke
				(width 0.1)
				(type default)
			)
			(layer "F.Fab")
		)
		(fp_line
			(start -0.12065 -0.305054)
			(end -0.12065 -0.2794)
			(stroke
				(width 0.1)
				(type default)
			)
			(layer "F.Fab")
		)
		(pad "1" smd circle
			(at -0.40005 0 270)
			(size 0 0)
			(layers "F.Cu" "F.Mask" "F.Paste")
			(net "BIC_RST_PWRGD_RSMRST_R")
		)
		(pad "2" smd circle
			(at 0.40005 0 270)
			(size 0 0)
			(layers "F.Cu" "F.Mask" "F.Paste")
			(net "BIC_RST_PWRGD_RSMRST")
		)
	)
	(footprint ""
		(layer "F.Cu")
		(at 154.860244 -117.7544 180)
		(property "Reference" "R108"
			(at 0 0 180)
			(layer "F.SilkS")
			(hide yes)
			(effects
				(font
					(size 1.27 1.27)
				)
			)
		)
		(property "Value" ""
			(at 0 0 180)
			(layer "F.Fab")
			(effects
				(font
					(size 1.27 1.27)
				)
			)
		)
		(duplicate_pad_numbers_are_jumpers no)
		(fp_line
			(start 0.7874 0.4064)
			(end -0.7874 0.4064)
			(stroke
				(width 0.1524)
				(type default)
			)
			(layer "F.SilkS")
		)
		(fp_line
			(start 0.7874 -0.4064)
			(end 0.7874 0.4064)
			(stroke
				(width 0.1524)
				(type default)
			)
			(layer "F.SilkS")
		)
		(fp_line
			(start -0.7874 0.4064)
			(end -0.7874 -0.4064)
			(stroke
				(width 0.1524)
				(type default)
			)
			(layer "F.SilkS")
		)
		(fp_line
			(start -0.7874 -0.4064)
			(end 0.7874 -0.4064)
			(stroke
				(width 0.1524)
				(type default)
			)
			(layer "F.SilkS")
		)
		(fp_line
			(start 0.67945 0.3048)
			(end 0.120396 0.3048)
			(stroke
				(width 0.1)
				(type default)
			)
			(layer "F.Fab")
		)
		(fp_line
			(start 0.67945 -0.3048)
			(end 0.67945 0.3048)
			(stroke
				(width 0.1)
				(type default)
			)
			(layer "F.Fab")
		)
		(fp_line
			(start 0.12065 -0.2794)
			(end 0.12065 -0.3048)
			(stroke
				(width 0.1)
				(type default)
			)
			(layer "F.Fab")
		)
		(fp_line
			(start 0.12065 -0.3048)
			(end 0.67945 -0.3048)
			(stroke
				(width 0.1)
				(type default)
			)
			(layer "F.Fab")
		)
		(fp_line
			(start 0.120396 0.3048)
			(end 0.120396 0.2794)
			(stroke
				(width 0.1)
				(type default)
			)
			(layer "F.Fab")
		)
		(fp_line
			(start 0.120396 0.2794)
			(end -0.12065 0.2794)
			(stroke
				(width 0.1)
				(type default)
			)
			(layer "F.Fab")
		)
		(fp_line
			(start -0.12065 0.3048)
			(end -0.67945 0.3048)
			(stroke
				(width 0.1)
				(type default)
			)
			(layer "F.Fab")
		)
		(fp_line
			(start -0.12065 0.2794)
			(end -0.12065 0.3048)
			(stroke
				(width 0.1)
				(type default)
			)
			(layer "F.Fab")
		)
		(fp_line
			(start -0.12065 -0.2794)
			(end 0.12065 -0.2794)
			(stroke
				(width 0.1)
				(type default)
			)
			(layer "F.Fab")
		)
		(fp_line
			(start -0.12065 -0.305054)
			(end -0.12065 -0.2794)
			(stroke
				(width 0.1)
				(type default)
			)
			(layer "F.Fab")
		)
		(fp_line
			(start -0.67945 0.3048)
			(end -0.67945 -0.305054)
			(stroke
				(width 0.1)
				(type default)
			)
			(layer "F.Fab")
		)
		(fp_line
			(start -0.67945 -0.305054)
			(end -0.12065 -0.305054)
			(stroke
				(width 0.1)
				(type default)
			)
			(layer "F.Fab")
		)
		(pad "1" smd circle
			(at -0.40005 0 180)
			(size 0 0)
			(layers "F.Cu" "F.Mask" "F.Paste")
			(net "PRSNTB0_NIC2_N")
		)
		(pad "2" smd circle
			(at 0.40005 0 180)
			(size 0 0)
			(layers "F.Cu" "F.Mask" "F.Paste")
			(net "P3V3_AUX")
		)
	)
	(footprint ""
		(layer "F.Cu")
		(at 444.908178 -223.316546 180)
		(property "Reference" "R6610"
			(at 0 0 180)
			(layer "F.SilkS")
			(hide yes)
			(effects
				(font
					(size 1.27 1.27)
				)
			)
		)
		(property "Value" ""
			(at 0 0 180)
			(layer "F.Fab")
			(effects
				(font
					(size 1.27 1.27)
				)
			)
		)
		(duplicate_pad_numbers_are_jumpers no)
		(fp_line
			(start 0.7874 0.4064)
			(end -0.7874 0.4064)
			(stroke
				(width 0.1524)
				(type default)
			)
			(layer "F.SilkS")
		)
		(fp_line
			(start 0.7874 -0.4064)
			(end 0.7874 0.4064)
			(stroke
				(width 0.1524)
				(type default)
			)
			(layer "F.SilkS")
		)
		(fp_line
			(start -0.7874 0.4064)
			(end -0.7874 -0.4064)
			(stroke
				(width 0.1524)
				(type default)
			)
			(layer "F.SilkS")
		)
		(fp_line
			(start -0.7874 -0.4064)
			(end 0.7874 -0.4064)
			(stroke
				(width 0.1524)
				(type default)
			)
			(layer "F.SilkS")
		)
		(fp_line
			(start 0.67945 0.3048)
			(end 0.120396 0.3048)
			(stroke
				(width 0.1)
				(type default)
			)
			(layer "F.Fab")
		)
		(fp_line
			(start 0.67945 -0.3048)
			(end 0.67945 0.3048)
			(stroke
				(width 0.1)
				(type default)
			)
			(layer "F.Fab")
		)
		(fp_line
			(start 0.12065 -0.2794)
			(end 0.12065 -0.3048)
			(stroke
				(width 0.1)
				(type default)
			)
			(layer "F.Fab")
		)
		(fp_line
			(start 0.12065 -0.3048)
			(end 0.67945 -0.3048)
			(stroke
				(width 0.1)
				(type default)
			)
			(layer "F.Fab")
		)
		(fp_line
			(start 0.120396 0.3048)
			(end 0.120396 0.2794)
			(stroke
				(width 0.1)
				(type default)
			)
			(layer "F.Fab")
		)
		(fp_line
			(start 0.120396 0.2794)
			(end -0.12065 0.2794)
			(stroke
				(width 0.1)
				(type default)
			)
			(layer "F.Fab")
		)
		(fp_line
			(start -0.12065 0.3048)
			(end -0.67945 0.3048)
			(stroke
				(width 0.1)
				(type default)
			)
			(layer "F.Fab")
		)
		(fp_line
			(start -0.12065 0.2794)
			(end -0.12065 0.3048)
			(stroke
				(width 0.1)
				(type default)
			)
			(layer "F.Fab")
		)
		(fp_line
			(start -0.12065 -0.2794)
			(end 0.12065 -0.2794)
			(stroke
				(width 0.1)
				(type default)
			)
			(layer "F.Fab")
		)
		(fp_line
			(start -0.12065 -0.305054)
			(end -0.12065 -0.2794)
			(stroke
				(width 0.1)
				(type default)
			)
			(layer "F.Fab")
		)
		(fp_line
			(start -0.67945 0.3048)
			(end -0.67945 -0.305054)
			(stroke
				(width 0.1)
				(type default)
			)
			(layer "F.Fab")
		)
		(fp_line
			(start -0.67945 -0.305054)
			(end -0.12065 -0.305054)
			(stroke
				(width 0.1)
				(type default)
			)
			(layer "F.Fab")
		)
		(pad "1" smd circle
			(at -0.40005 0 180)
			(size 0 0)
			(layers "F.Cu" "F.Mask" "F.Paste")
			(net "UART_PEX2_SDB_CP2108_RX")
		)
		(pad "2" smd circle
			(at 0.40005 0 180)
			(size 0 0)
			(layers "F.Cu" "F.Mask" "F.Paste")
			(net "UART_PEX2_SDB_R_RX")
		)
	)
	(footprint ""
		(layer "F.Cu")
		(at 268.838426 -120.113298)
		(property "Reference" "C470"
			(at 0 0 0)
			(layer "F.SilkS")
			(hide yes)
			(effects
				(font
					(size 1.27 1.27)
				)
			)
		)
		(property "Value" ""
			(at 0 0 0)
			(layer "F.Fab")
			(effects
				(font
					(size 1.27 1.27)
				)
			)
		)
		(duplicate_pad_numbers_are_jumpers no)
		(fp_line
			(start -0.299974 -0.150114)
			(end 0.299974 -0.150114)
			(stroke
				(width 0.1)
				(type default)
			)
			(layer "F.Fab")
		)
		(fp_line
			(start -0.299974 0.150114)
			(end -0.299974 -0.150114)
			(stroke
				(width 0.1)
				(type default)
			)
			(layer "F.Fab")
		)
		(fp_line
			(start 0.299974 -0.150114)
			(end 0.299974 0.150114)
			(stroke
				(width 0.1)
				(type default)
			)
			(layer "F.Fab")
		)
		(fp_line
			(start 0.299974 0.150114)
			(end -0.299974 0.150114)
			(stroke
				(width 0.1)
				(type default)
			)
			(layer "F.Fab")
		)
		(pad "1" smd rect
			(at -0.2667 0)
			(size 0.3048 0.381)
			(layers "F.Cu" "F.Mask" "F.Paste")
			(net "P5E_PEX2_STN1_TX_DN<24>")
		)
		(pad "2" smd rect
			(at 0.2667 0)
			(size 0.3048 0.381)
			(layers "F.Cu" "F.Mask" "F.Paste")
			(net "P5E_PEX2_STN1_TX_C_DN<24>")
		)
	)
)
